# T6G (Grand Teton) — schematic netlist excerpt (pin names and nets, part order shuffled) for the footprints in the layout excerpt that follows; sources: Cadence DE-HDL packaged netlist, KiCad conversion of 04192023_DAF0TMB3IC0_F0TG_MB_C_brd_V02_OCP.brd

R1822  Q_RES  10K 1% CHIP  pkg 0402LF  page 250 : A = P3V3_AUX ; B = RST_SMB_SWITCH_N
C6018  Q_CAP  0.1UF 25V 10% X7R  pkg 0402  page 180 : A = USB3_CPU0_BMC_RX_HUB2_DN ; B = USB3_CPU0_BMC_RX_HUB_C_DN

(kicad_pcb
	(version 20260206)
	(generator "pcbnew")
	(generator_version "10.0")
	(general
		(thickness 1.6)
		(legacy_teardrops no)
	)
	(paper "A4")
	(title_block
		(title "04192023_DAF0TMB3IC0_F0TG_MB_C_brd_V02_OCP.brd")
		(comment 1 "Grand Teton / footprints 886-887 of 8354")
	)
	(layers
		(0 "F.Cu" signal "TOP")
		(4 "In1.Cu" signal "GND")
		(6 "In2.Cu" signal "IN1")
		(8 "In3.Cu" signal "GND1")
		(10 "In4.Cu" signal "IN2")
		(12 "In5.Cu" signal "GND2")
		(14 "In6.Cu" signal "IN3")
		(16 "In7.Cu" signal "GND3")
		(18 "In8.Cu" signal "VCC")
		(20 "In9.Cu" signal "VCC1")
		(22 "In10.Cu" signal "GND4")
		(24 "In11.Cu" signal "IN4")
		(26 "In12.Cu" signal "GND5")
		(28 "In13.Cu" signal "IN5")
		(30 "In14.Cu" signal "GND6")
		(32 "In15.Cu" signal "IN6")
		(34 "In16.Cu" signal "GND7")
		(2 "B.Cu" signal "BOTTOM")
		(9 "F.Adhes" user "F.Adhesive")
		(11 "B.Adhes" user "B.Adhesive")
		(13 "F.Paste" user "Package Geometry/Pastemask Top")
		(15 "B.Paste" user "Package Geometry/Pastemask Bottom")
		(5 "F.SilkS" user "Ref Des/Silkscreen Top")
		(7 "B.SilkS" user "Ref Des/Silkscreen Bottom")
		(1 "F.Mask" user "Board Geometry/Soldermask Top")
		(3 "B.Mask" user "Board Geometry/Soldermask Bottom")
		(17 "Dwgs.User" user "User.Drawings")
		(19 "Cmts.User" user "User.Comments")
		(21 "Eco1.User" user "User.Eco1")
		(23 "Eco2.User" user "User.Eco2")
		(25 "Edge.Cuts" user "Board Geometry/Outline")
		(27 "Margin" user)
		(31 "F.CrtYd" user "Package Geometry/Place Bound Top")
		(29 "B.CrtYd" user "Package Geometry/Place Bound Bottom")
		(35 "F.Fab" user "Ref Des/Assembly Top")
		(33 "B.Fab" user "Ref Des/Assembly Bottom")
	)
	(footprint ""
		(layer "F.Cu")
		(at 140.02512 -30.82671 90)
		(property "Reference" "C6018"
			(at 0 0 90)
			(layer "F.SilkS")
			(hide yes)
			(effects
				(font
					(size 1.27 1.27)
				)
			)
		)
		(property "Value" ""
			(at 0 0 90)
			(layer "F.Fab")
			(effects
				(font
					(size 1.27 1.27)
				)
			)
		)
		(duplicate_pad_numbers_are_jumpers no)
		(fp_line
			(start 0.7874 -0.4064)
			(end 0.7874 0.4064)
			(stroke
				(width 0.1524)
				(type default)
			)
			(layer "F.SilkS")
		)
		(fp_line
			(start -0.7874 -0.4064)
			(end 0.7874 -0.4064)
			(stroke
				(width 0.1524)
				(type default)
			)
			(layer "F.SilkS")
		)
		(fp_line
			(start 0.7874 0.4064)
			(end -0.7874 0.4064)
			(stroke
				(width 0.1524)
				(type default)
			)
			(layer "F.SilkS")
		)
		(fp_line
			(start -0.7874 0.4064)
			(end -0.7874 -0.4064)
			(stroke
				(width 0.1524)
				(type default)
			)
			(layer "F.SilkS")
		)
		(fp_line
			(start 0.6858 -0.3048)
			(end 0.6858 0.3048)
			(stroke
				(width 0.1)
				(type default)
			)
			(layer "F.Fab")
		)
		(fp_line
			(start 0.1016 -0.3048)
			(end 0.6858 -0.3048)
			(stroke
				(width 0.1)
				(type default)
			)
			(layer "F.Fab")
		)
		(fp_line
			(start -0.1016 -0.3048)
			(end -0.1016 -0.2794)
			(stroke
				(width 0.1)
				(type default)
			)
			(layer "F.Fab")
		)
		(fp_line
			(start -0.6858 -0.3048)
			(end -0.1016 -0.3048)
			(stroke
				(width 0.1)
				(type default)
			)
			(layer "F.Fab")
		)
		(fp_line
			(start 0.1016 -0.2794)
			(end 0.1016 -0.3048)
			(stroke
				(width 0.1)
				(type default)
			)
			(layer "F.Fab")
		)
		(fp_line
			(start -0.1016 -0.2794)
			(end 0.1016 -0.2794)
			(stroke
				(width 0.1)
				(type default)
			)
			(layer "F.Fab")
		)
		(fp_line
			(start 0.1016 0.2794)
			(end -0.1016 0.2794)
			(stroke
				(width 0.1)
				(type default)
			)
			(layer "F.Fab")
		)
		(fp_line
			(start -0.1016 0.2794)
			(end -0.1016 0.3048)
			(stroke
				(width 0.1)
				(type default)
			)
			(layer "F.Fab")
		)
		(fp_line
			(start 0.6858 0.3048)
			(end 0.1016 0.3048)
			(stroke
				(width 0.1)
				(type default)
			)
			(layer "F.Fab")
		)
		(fp_line
			(start 0.1016 0.3048)
			(end 0.1016 0.2794)
			(stroke
				(width 0.1)
				(type default)
			)
			(layer "F.Fab")
		)
		(fp_line
			(start -0.1016 0.3048)
			(end -0.6858 0.3048)
			(stroke
				(width 0.1)
				(type default)
			)
			(layer "F.Fab")
		)
		(fp_line
			(start -0.6858 0.3048)
			(end -0.6858 -0.3048)
			(stroke
				(width 0.1)
				(type default)
			)
			(layer "F.Fab")
		)
		(pad "1" smd rect
			(at -0.40005 0 270)
			(size 0.4572 0.508)
			(layers "F.Cu" "F.Mask" "F.Paste")
			(net "USB3_CPU0_BMC_RX_HUB2_DN")
		)
		(pad "2" smd rect
			(at 0.40005 0 270)
			(size 0.4572 0.508)
			(layers "F.Cu" "F.Mask" "F.Paste")
			(net "USB3_CPU0_BMC_RX_HUB_C_DN")
		)
	)
	(footprint ""
		(layer "F.Cu")
		(at 277.352252 -123.08967)
		(property "Reference" "R1822"
			(at 0 0 0)
			(layer "F.SilkS")
			(hide yes)
			(effects
				(font
					(size 1.27 1.27)
				)
			)
		)
		(property "Value" ""
			(at 0 0 0)
			(layer "F.Fab")
			(effects
				(font
					(size 1.27 1.27)
				)
			)
		)
		(duplicate_pad_numbers_are_jumpers no)
		(fp_line
			(start -0.7874 -0.4064)
			(end 0.7874 -0.4064)
			(stroke
				(width 0.1524)
				(type default)
			)
			(layer "F.SilkS")
		)
		(fp_line
			(start -0.7874 0.4064)
			(end -0.7874 -0.4064)
			(stroke
				(width 0.1524)
				(type default)
			)
			(layer "F.SilkS")
		)
		(fp_line
			(start 0.7874 -0.4064)
			(end 0.7874 0.4064)
			(stroke
				(width 0.1524)
				(type default)
			)
			(layer "F.SilkS")
		)
		(fp_line
			(start 0.7874 0.4064)
			(end -0.7874 0.4064)
			(stroke
				(width 0.1524)
				(type default)
			)
			(layer "F.SilkS")
		)
		(fp_line
			(start -0.67945 -0.305054)
			(end -0.12065 -0.305054)
			(stroke
				(width 0.1)
				(type default)
			)
			(layer "F.Fab")
		)
		(fp_line
			(start -0.67945 0.3048)
			(end -0.67945 -0.305054)
			(stroke
				(width 0.1)
				(type default)
			)
			(layer "F.Fab")
		)
		(fp_line
			(start -0.12065 -0.305054)
			(end -0.12065 -0.2794)
			(stroke
				(width 0.1)
				(type default)
			)
			(layer "F.Fab")
		)
		(fp_line
			(start -0.12065 -0.2794)
			(end 0.12065 -0.2794)
			(stroke
				(width 0.1)
				(type default)
			)
			(layer "F.Fab")
		)
		(fp_line
			(start -0.12065 0.2794)
			(end -0.12065 0.3048)
			(stroke
				(width 0.1)
				(type default)
			)
			(layer "F.Fab")
		)
		(fp_line
			(start -0.12065 0.3048)
			(end -0.67945 0.3048)
			(stroke
				(width 0.1)
				(type default)
			)
			(layer "F.Fab")
		)
		(fp_line
			(start 0.120396 0.2794)
			(end -0.12065 0.2794)
			(stroke
				(width 0.1)
				(type default)
			)
			(layer "F.Fab")
		)
		(fp_line
			(start 0.120396 0.3048)
			(end 0.120396 0.2794)
			(stroke
				(width 0.1)
				(type default)
			)
			(layer "F.Fab")
		)
		(fp_line
			(start 0.12065 -0.3048)
			(end 0.67945 -0.3048)
			(stroke
				(width 0.1)
				(type default)
			)
			(layer "F.Fab")
		)
		(fp_line
			(start 0.12065 -0.2794)
			(end 0.12065 -0.3048)
			(stroke
				(width 0.1)
				(type default)
			)
			(layer "F.Fab")
		)
		(fp_line
			(start 0.67945 -0.3048)
			(end 0.67945 0.3048)
			(stroke
				(width 0.1)
				(type default)
			)
			(layer "F.Fab")
		)
		(fp_line
			(start 0.67945 0.3048)
			(end 0.120396 0.3048)
			(stroke
				(width 0.1)
				(type default)
			)
			(layer "F.Fab")
		)
		(pad "1" smd circle
			(at -0.40005 0)
			(size 0 0)
			(layers "F.Cu" "F.Mask" "F.Paste")
			(net "P3V3_AUX")
		)
		(pad "2" smd circle
			(at 0.40005 0)
			(size 0 0)
			(layers "F.Cu" "F.Mask" "F.Paste")
			(net "RST_SMB_SWITCH_N")
		)
	)
)
